(kicad_pcb
	(version 20260206)
	(generator "pcbnew")
	(generator_version "10.0")
	(general
		(thickness 1.6)
		(legacy_teardrops no)
	)
	(paper "A4")
	(title_block
		(title "01162023_DA0F0TEBIF0_F0T_Expander_BD_F_brd_V02_OCP.brd")
		(comment 1 "Grand Teton / footprints 5824-5828 of 9728")
	)
	(layers
		(0 "F.Cu" signal "TOP")
		(4 "In1.Cu" signal "GND")
		(6 "In2.Cu" signal "VCC")
		(8 "In3.Cu" signal "VCC1")
		(10 "In4.Cu" signal "GND1")
		(12 "In5.Cu" signal "IN1")
		(14 "In6.Cu" signal "GND2")
		(16 "In7.Cu" signal "IN2")
		(18 "In8.Cu" signal "GND3")
		(20 "In9.Cu" signal "IN3")
		(22 "In10.Cu" signal "GND4")
		(24 "In11.Cu" signal "IN4")
		(26 "In12.Cu" signal "GND5")
		(28 "In13.Cu" signal "IN5")
		(30 "In14.Cu" signal "GND6")
		(32 "In15.Cu" signal "IN6")
		(34 "In16.Cu" signal "GND7")
		(2 "B.Cu" signal "BOTTOM")
		(9 "F.Adhes" user "F.Adhesive")
		(11 "B.Adhes" user "B.Adhesive")
		(13 "F.Paste" user "Package Geometry/Pastemask Top")
		(15 "B.Paste" user "Package Geometry/Pastemask Bottom")
		(5 "F.SilkS" user "Ref Des/Silkscreen Top")
		(7 "B.SilkS" user "Ref Des/Silkscreen Bottom")
		(1 "F.Mask" user "Board Geometry/Soldermask Top")
		(3 "B.Mask" user "Board Geometry/Soldermask Bottom")
		(17 "Dwgs.User" user "User.Drawings")
		(19 "Cmts.User" user "User.Comments")
		(21 "Eco1.User" user "User.Eco1")
		(23 "Eco2.User" user "User.Eco2")
		(25 "Edge.Cuts" user "Board Geometry/Outline")
		(27 "Margin" user)
		(31 "F.CrtYd" user "Package Geometry/Place Bound Top")
		(29 "B.CrtYd" user "Package Geometry/Place Bound Bottom")
		(35 "F.Fab" user "Ref Des/Assembly Top")
		(33 "B.Fab" user "Ref Des/Assembly Bottom")
	)
	(footprint ""
		(layer "F.Cu")
		(at 198.564246 -365.615728 180)
		(property "Reference" "PC9"
			(at 0 0 180)
			(layer "F.SilkS")
			(hide yes)
			(effects
				(font
					(size 1.27 1.27)
				)
			)
		)
		(property "Value" ""
			(at 0 0 180)
			(layer "F.Fab")
			(effects
				(font
					(size 1.27 1.27)
				)
			)
		)
		(duplicate_pad_numbers_are_jumpers no)
		(fp_line
			(start 0.7874 0.4064)
			(end -0.7874 0.4064)
			(stroke
				(width 0.1524)
				(type default)
			)
			(layer "F.SilkS")
		)
		(fp_line
			(start 0.7874 -0.4064)
			(end 0.7874 0.4064)
			(stroke
				(width 0.1524)
				(type default)
			)
			(layer "F.SilkS")
		)
		(fp_line
			(start -0.7874 0.4064)
			(end -0.7874 -0.4064)
			(stroke
				(width 0.1524)
				(type default)
			)
			(layer "F.SilkS")
		)
		(fp_line
			(start -0.7874 -0.4064)
			(end 0.7874 -0.4064)
			(stroke
				(width 0.1524)
				(type default)
			)
			(layer "F.SilkS")
		)
		(fp_line
			(start 0.67945 0.3048)
			(end 0.120396 0.3048)
			(stroke
				(width 0.1)
				(type default)
			)
			(layer "F.Fab")
		)
		(fp_line
			(start 0.67945 -0.3048)
			(end 0.67945 0.3048)
			(stroke
				(width 0.1)
				(type default)
			)
			(layer "F.Fab")
		)
		(fp_line
			(start 0.12065 -0.2794)
			(end 0.12065 -0.3048)
			(stroke
				(width 0.1)
				(type default)
			)
			(layer "F.Fab")
		)
		(fp_line
			(start 0.12065 -0.3048)
			(end 0.67945 -0.3048)
			(stroke
				(width 0.1)
				(type default)
			)
			(layer "F.Fab")
		)
		(fp_line
			(start 0.120396 0.3048)
			(end 0.120396 0.2794)
			(stroke
				(width 0.1)
				(type default)
			)
			(layer "F.Fab")
		)
		(fp_line
			(start 0.120396 0.2794)
			(end -0.12065 0.2794)
			(stroke
				(width 0.1)
				(type default)
			)
			(layer "F.Fab")
		)
		(fp_line
			(start -0.12065 0.3048)
			(end -0.67945 0.3048)
			(stroke
				(width 0.1)
				(type default)
			)
			(layer "F.Fab")
		)
		(fp_line
			(start -0.12065 0.2794)
			(end -0.12065 0.3048)
			(stroke
				(width 0.1)
				(type default)
			)
			(layer "F.Fab")
		)
		(fp_line
			(start -0.12065 -0.2794)
			(end 0.12065 -0.2794)
			(stroke
				(width 0.1)
				(type default)
			)
			(layer "F.Fab")
		)
		(fp_line
			(start -0.12065 -0.305054)
			(end -0.12065 -0.2794)
			(stroke
				(width 0.1)
				(type default)
			)
			(layer "F.Fab")
		)
		(fp_line
			(start -0.67945 0.3048)
			(end -0.67945 -0.305054)
			(stroke
				(width 0.1)
				(type default)
			)
			(layer "F.Fab")
		)
		(fp_line
			(start -0.67945 -0.305054)
			(end -0.12065 -0.305054)
			(stroke
				(width 0.1)
				(type default)
			)
			(layer "F.Fab")
		)
		(pad "1" smd circle
			(at -0.40005 0 180)
			(size 0 0)
			(layers "F.Cu" "F.Mask" "F.Paste")
			(net "HSC_VDD18")
		)
		(pad "2" smd circle
			(at 0.40005 0 180)
			(size 0 0)
			(layers "F.Cu" "F.Mask" "F.Paste")
			(net "AGND_HSC")
		)
	)
	(footprint ""
		(layer "F.Cu")
		(at 149.080728 -383.460498 180)
		(property "Reference" "R1848"
			(at 0 0 180)
			(layer "F.SilkS")
			(hide yes)
			(effects
				(font
					(size 1.27 1.27)
				)
			)
		)
		(property "Value" ""
			(at 0 0 180)
			(layer "F.Fab")
			(effects
				(font
					(size 1.27 1.27)
				)
			)
		)
		(duplicate_pad_numbers_are_jumpers no)
		(fp_line
			(start 0.7874 0.4064)
			(end -0.7874 0.4064)
			(stroke
				(width 0.1524)
				(type default)
			)
			(layer "F.SilkS")
		)
		(fp_line
			(start 0.7874 -0.4064)
			(end 0.7874 0.4064)
			(stroke
				(width 0.1524)
				(type default)
			)
			(layer "F.SilkS")
		)
		(fp_line
			(start -0.7874 0.4064)
			(end -0.7874 -0.4064)
			(stroke
				(width 0.1524)
				(type default)
			)
			(layer "F.SilkS")
		)
		(fp_line
			(start -0.7874 -0.4064)
			(end 0.7874 -0.4064)
			(stroke
				(width 0.1524)
				(type default)
			)
			(layer "F.SilkS")
		)
		(fp_line
			(start 0.67945 0.3048)
			(end 0.120396 0.3048)
			(stroke
				(width 0.1)
				(type default)
			)
			(layer "F.Fab")
		)
		(fp_line
			(start 0.67945 -0.3048)
			(end 0.67945 0.3048)
			(stroke
				(width 0.1)
				(type default)
			)
			(layer "F.Fab")
		)
		(fp_line
			(start 0.12065 -0.2794)
			(end 0.12065 -0.3048)
			(stroke
				(width 0.1)
				(type default)
			)
			(layer "F.Fab")
		)
		(fp_line
			(start 0.12065 -0.3048)
			(end 0.67945 -0.3048)
			(stroke
				(width 0.1)
				(type default)
			)
			(layer "F.Fab")
		)
		(fp_line
			(start 0.120396 0.3048)
			(end 0.120396 0.2794)
			(stroke
				(width 0.1)
				(type default)
			)
			(layer "F.Fab")
		)
		(fp_line
			(start 0.120396 0.2794)
			(end -0.12065 0.2794)
			(stroke
				(width 0.1)
				(type default)
			)
			(layer "F.Fab")
		)
		(fp_line
			(start -0.12065 0.3048)
			(end -0.67945 0.3048)
			(stroke
				(width 0.1)
				(type default)
			)
			(layer "F.Fab")
		)
		(fp_line
			(start -0.12065 0.2794)
			(end -0.12065 0.3048)
			(stroke
				(width 0.1)
				(type default)
			)
			(layer "F.Fab")
		)
		(fp_line
			(start -0.12065 -0.2794)
			(end 0.12065 -0.2794)
			(stroke
				(width 0.1)
				(type default)
			)
			(layer "F.Fab")
		)
		(fp_line
			(start -0.12065 -0.305054)
			(end -0.12065 -0.2794)
			(stroke
				(width 0.1)
				(type default)
			)
			(layer "F.Fab")
		)
		(fp_line
			(start -0.67945 0.3048)
			(end -0.67945 -0.305054)
			(stroke
				(width 0.1)
				(type default)
			)
			(layer "F.Fab")
		)
		(fp_line
			(start -0.67945 -0.305054)
			(end -0.12065 -0.305054)
			(stroke
				(width 0.1)
				(type default)
			)
			(layer "F.Fab")
		)
		(pad "1" smd circle
			(at -0.40005 0 180)
			(size 0 0)
			(layers "F.Cu" "F.Mask" "F.Paste")
			(net "RST_GPU_FPGA_EROT_R_N")
		)
		(pad "2" smd circle
			(at 0.40005 0 180)
			(size 0 0)
			(layers "F.Cu" "F.Mask" "F.Paste")
			(net "RST_GPU_FPGA_EROT_N")
		)
	)
	(footprint ""
		(layer "F.Cu")
		(at 115.356386 -82.46999 180)
		(property "Reference" "R1142"
			(at 0 0 180)
			(layer "F.SilkS")
			(hide yes)
			(effects
				(font
					(size 1.27 1.27)
				)
			)
		)
		(property "Value" ""
			(at 0 0 180)
			(layer "F.Fab")
			(effects
				(font
					(size 1.27 1.27)
				)
			)
		)
		(duplicate_pad_numbers_are_jumpers no)
		(fp_line
			(start -0.7874 -0.4064)
			(end 0.7874 -0.4064)
			(stroke
				(width 0.1524)
				(type default)
			)
			(layer "F.SilkS")
		)
		(fp_line
			(start 0.67945 0.3048)
			(end 0.120396 0.3048)
			(stroke
				(width 0.1)
				(type default)
			)
			(layer "F.Fab")
		)
		(fp_line
			(start 0.67945 -0.3048)
			(end 0.67945 0.3048)
			(stroke
				(width 0.1)
				(type default)
			)
			(layer "F.Fab")
		)
		(fp_line
			(start 0.12065 -0.2794)
			(end 0.12065 -0.3048)
			(stroke
				(width 0.1)
				(type default)
			)
			(layer "F.Fab")
		)
		(fp_line
			(start 0.12065 -0.3048)
			(end 0.67945 -0.3048)
			(stroke
				(width 0.1)
				(type default)
			)
			(layer "F.Fab")
		)
		(fp_line
			(start 0.120396 0.3048)
			(end 0.120396 0.2794)
			(stroke
				(width 0.1)
				(type default)
			)
			(layer "F.Fab")
		)
		(fp_line
			(start 0.120396 0.2794)
			(end -0.12065 0.2794)
			(stroke
				(width 0.1)
				(type default)
			)
			(layer "F.Fab")
		)
		(fp_line
			(start -0.12065 0.3048)
			(end -0.67945 0.3048)
			(stroke
				(width 0.1)
				(type default)
			)
			(layer "F.Fab")
		)
		(fp_line
			(start -0.12065 0.2794)
			(end -0.12065 0.3048)
			(stroke
				(width 0.1)
				(type default)
			)
			(layer "F.Fab")
		)
		(fp_line
			(start -0.12065 -0.2794)
			(end 0.12065 -0.2794)
			(stroke
				(width 0.1)
				(type default)
			)
			(layer "F.Fab")
		)
		(fp_line
			(start -0.12065 -0.305054)
			(end -0.12065 -0.2794)
			(stroke
				(width 0.1)
				(type default)
			)
			(layer "F.Fab")
		)
		(fp_line
			(start -0.67945 0.3048)
			(end -0.67945 -0.305054)
			(stroke
				(width 0.1)
				(type default)
			)
			(layer "F.Fab")
		)
		(fp_line
			(start -0.67945 -0.305054)
			(end -0.12065 -0.305054)
			(stroke
				(width 0.1)
				(type default)
			)
			(layer "F.Fab")
		)
		(pad "1" smd circle
			(at -0.40005 0 180)
			(size 0 0)
			(layers "F.Cu" "F.Mask" "F.Paste")
			(net "CLK_100M_DB800ZL_SSD3_R_DP")
		)
		(pad "2" smd circle
			(at 0.40005 0 180)
			(size 0 0)
			(layers "F.Cu" "F.Mask" "F.Paste")
			(net "CLK_100M_DB800ZL_SSD3_DP")
		)
	)
	(footprint ""
		(layer "F.Cu")
		(at 254.471678 -152.71115 90)
		(property "Reference" "R725"
			(at 0 0 90)
			(layer "F.SilkS")
			(hide yes)
			(effects
				(font
					(size 1.27 1.27)
				)
			)
		)
		(property "Value" ""
			(at 0 0 90)
			(layer "F.Fab")
			(effects
				(font
					(size 1.27 1.27)
				)
			)
		)
		(duplicate_pad_numbers_are_jumpers no)
		(fp_line
			(start 0.7874 -0.4064)
			(end 0.7874 0.4064)
			(stroke
				(width 0.1524)
				(type default)
			)
			(layer "F.SilkS")
		)
		(fp_line
			(start -0.7874 -0.4064)
			(end 0.7874 -0.4064)
			(stroke
				(width 0.1524)
				(type default)
			)
			(layer "F.SilkS")
		)
		(fp_line
			(start 0.7874 0.4064)
			(end -0.7874 0.4064)
			(stroke
				(width 0.1524)
				(type default)
			)
			(layer "F.SilkS")
		)
		(fp_line
			(start -0.7874 0.4064)
			(end -0.7874 -0.4064)
			(stroke
				(width 0.1524)
				(type default)
			)
			(layer "F.SilkS")
		)
		(fp_line
			(start -0.12065 -0.305054)
			(end -0.12065 -0.2794)
			(stroke
				(width 0.1)
				(type default)
			)
			(layer "F.Fab")
		)
		(fp_line
			(start -0.67945 -0.305054)
			(end -0.12065 -0.305054)
			(stroke
				(width 0.1)
				(type default)
			)
			(layer "F.Fab")
		)
		(fp_line
			(start 0.67945 -0.3048)
			(end 0.67945 0.3048)
			(stroke
				(width 0.1)
				(type default)
			)
			(layer "F.Fab")
		)
		(fp_line
			(start 0.12065 -0.3048)
			(end 0.67945 -0.3048)
			(stroke
				(width 0.1)
				(type default)
			)
			(layer "F.Fab")
		)
		(fp_line
			(start 0.12065 -0.2794)
			(end 0.12065 -0.3048)
			(stroke
				(width 0.1)
				(type default)
			)
			(layer "F.Fab")
		)
		(fp_line
			(start -0.12065 -0.2794)
			(end 0.12065 -0.2794)
			(stroke
				(width 0.1)
				(type default)
			)
			(layer "F.Fab")
		)
		(fp_line
			(start 0.120396 0.2794)
			(end -0.12065 0.2794)
			(stroke
				(width 0.1)
				(type default)
			)
			(layer "F.Fab")
		)
		(fp_line
			(start -0.12065 0.2794)
			(end -0.12065 0.3048)
			(stroke
				(width 0.1)
				(type default)
			)
			(layer "F.Fab")
		)
		(fp_line
			(start 0.67945 0.3048)
			(end 0.120396 0.3048)
			(stroke
				(width 0.1)
				(type default)
			)
			(layer "F.Fab")
		)
		(fp_line
			(start 0.120396 0.3048)
			(end 0.120396 0.2794)
			(stroke
				(width 0.1)
				(type default)
			)
			(layer "F.Fab")
		)
		(fp_line
			(start -0.12065 0.3048)
			(end -0.67945 0.3048)
			(stroke
				(width 0.1)
				(type default)
			)
			(layer "F.Fab")
		)
		(fp_line
			(start -0.67945 0.3048)
			(end -0.67945 -0.305054)
			(stroke
				(width 0.1)
				(type default)
			)
			(layer "F.Fab")
		)
		(pad "1" smd circle
			(at -0.40005 0 90)
			(size 0 0)
			(layers "F.Cu" "F.Mask" "F.Paste")
			(net "NIC4_ADC_A1")
		)
		(pad "2" smd circle
			(at 0.40005 0 90)
			(size 0 0)
			(layers "F.Cu" "F.Mask" "F.Paste")
			(net "P3V3_AUX")
		)
	)
	(footprint ""
		(layer "F.Cu")
		(at 423.145966 -46.4439 180)
		(property "Reference" "U77"
			(at 0.540766 -2.45237 0)
			(unlocked yes)
			(layer "F.SilkS")
			(effects
				(font
					(size 0.7874 0.5842)
					(thickness 0.1524)
				)
			)
		)
		(property "Value" ""
			(at 0 0 180)
			(layer "F.Fab")
			(effects
				(font
					(size 1.27 1.27)
				)
			)
		)
		(duplicate_pad_numbers_are_jumpers no)
		(fp_line
			(start 1.500124 1.500124)
			(end 1.004062 1.500124)
			(stroke
				(width 0.1524)
				(type default)
			)
			(layer "F.SilkS")
		)
		(fp_line
			(start 1.500124 1.004062)
			(end 1.500124 1.500124)
			(stroke
				(width 0.1524)
				(type default)
			)
			(layer "F.SilkS")
		)
		(fp_line
			(start 1.500124 -1.500124)
			(end 1.500124 -1.004062)
			(stroke
				(width 0.1524)
				(type default)
			)
			(layer "F.SilkS")
		)
		(fp_line
			(start 1.004062 -1.500124)
			(end 1.500124 -1.500124)
			(stroke
				(width 0.1524)
				(type default)
			)
			(layer "F.SilkS")
		)
		(fp_line
			(start -1.004062 1.500124)
			(end -1.500124 1.500124)
			(stroke
				(width 0.1524)
				(type default)
			)
			(layer "F.SilkS")
		)
		(fp_line
			(start -1.500124 1.500124)
			(end -1.500124 1.004062)
			(stroke
				(width 0.1524)
				(type default)
			)
			(layer "F.SilkS")
		)
		(fp_line
			(start -1.500124 -1.004062)
			(end -1.500124 -1.500124)
			(stroke
				(width 0.1524)
				(type default)
			)
			(layer "F.SilkS")
		)
		(fp_line
			(start -1.500124 -1.500124)
			(end -1.004062 -1.500124)
			(stroke
				(width 0.1524)
				(type default)
			)
			(layer "F.SilkS")
		)
		(fp_poly
			(pts
				(xy -1.725168 -2.612136) (xy -2.44348 -1.89357) (xy -1.366012 -1.534414)
			)
			(stroke
				(width 0)
				(type default)
			)
			(fill yes)
			(layer "F.SilkS")
		)
		(fp_line
			(start 1.500124 1.500124)
			(end -1.500124 1.500124)
			(stroke
				(width 0.1)
				(type default)
			)
			(layer "F.Fab")
		)
		(fp_line
			(start 1.500124 -1.500124)
			(end 1.500124 1.500124)
			(stroke
				(width 0.1)
				(type default)
			)
			(layer "F.Fab")
		)
		(fp_line
			(start -1.500124 1.500124)
			(end -1.500124 -1.500124)
			(stroke
				(width 0.1)
				(type default)
			)
			(layer "F.Fab")
		)
		(fp_line
			(start -1.500124 -1.500124)
			(end 1.500124 -1.500124)
			(stroke
				(width 0.1)
				(type default)
			)
			(layer "F.Fab")
		)
		(fp_poly
			(pts
				(xy -2.847848 -1.258062) (xy -2.847848 -0.242062) (xy -1.831848 -0.750062)
			)
			(stroke
				(width 0)
				(type default)
			)
			(fill yes)
			(layer "F.Fab")
		)
		(pad "1" smd rect
			(at -1.400048 -0.750062 90)
			(size 0.2286 0.6096)
			(layers "F.Cu" "F.Mask" "F.Paste")
			(net "SSD14_ADC_A1")
		)
		(pad "2" smd rect
			(at -1.400048 -0.249936 90)
			(size 0.2286 0.6096)
			(layers "F.Cu" "F.Mask" "F.Paste")
			(net "SSD14_ADC_A0")
		)
		(pad "3" smd rect
			(at -1.400048 0.249936 90)
			(size 0.2286 0.6096)
			(layers "F.Cu" "F.Mask" "F.Paste")
			(net "SSD14_ADC_ALERT_N")
		)
		(pad "4" smd rect
			(at -1.400048 0.750062 90)
			(size 0.2286 0.6096)
			(layers "F.Cu" "F.Mask" "F.Paste")
			(net "SMB_SSD14_ADC_SDA")
		)
		(pad "5" smd rect
			(at -0.750062 1.400048 180)
			(size 0.2286 0.6096)
			(layers "F.Cu" "F.Mask" "F.Paste")
			(net "SMB_SSD14_ADC_SCL")
		)
		(pad "6" smd rect
			(at -0.249936 1.400048 180)
			(size 0.2286 0.6096)
			(layers "F.Cu" "F.Mask" "F.Paste")
			(net "Net_8678")
		)
		(pad "7" smd rect
			(at 0.249936 1.400048 180)
			(size 0.2286 0.6096)
			(layers "F.Cu" "F.Mask" "F.Paste")
			(net "Net_8677")
		)
		(pad "8" smd rect
			(at 0.750062 1.400048 180)
			(size 0.2286 0.6096)
			(layers "F.Cu" "F.Mask" "F.Paste")
			(net "Net_8676")
		)
		(pad "9" smd rect
			(at 1.400048 0.750062 90)
			(size 0.2286 0.6096)
			(layers "F.Cu" "F.Mask" "F.Paste")
			(net "P3V3_AUX")
		)
		(pad "10" smd rect
			(at 1.400048 0.249936 90)
			(size 0.2286 0.6096)
			(layers "F.Cu" "F.Mask" "F.Paste")
			(net "GND")
		)
		(pad "11" smd rect
			(at 1.400048 -0.249936 90)
			(size 0.2286 0.6096)
			(layers "F.Cu" "F.Mask" "F.Paste")
			(net "P12V_SSD14_R")
		)
		(pad "12" smd rect
			(at 1.400048 -0.750062 90)
			(size 0.2286 0.6096)
			(layers "F.Cu" "F.Mask" "F.Paste")
			(net "P12V_SSD14_VIN_N")
		)
		(pad "13" smd rect
			(at 0.750062 -1.400048 180)
			(size 0.2286 0.6096)
			(layers "F.Cu" "F.Mask" "F.Paste")
			(net "P12V_SSD14_VIN_P")
		)
		(pad "14" smd rect
			(at 0.249936 -1.400048 180)
			(size 0.2286 0.6096)
			(layers "F.Cu" "F.Mask" "F.Paste")
			(net "Net_8675")
		)
		(pad "15" smd rect
			(at -0.249936 -1.400048 180)
			(size 0.2286 0.6096)
			(layers "F.Cu" "F.Mask" "F.Paste")
			(net "Net_8674")
		)
		(pad "16" smd rect
			(at -0.750062 -1.400048 180)
			(size 0.2286 0.6096)
			(layers "F.Cu" "F.Mask" "F.Paste")
			(net "Net_8673")
		)
		(pad "TH" smd rect
			(at 0 0 180)
			(size 1.7018 1.7018)
			(layers "F.Cu" "F.Mask" "F.Paste")
			(net "GND")
		)
		(zone
			(layer "F.Cu")
			(hatch none 0.5)
			(connect_pads
				(clearance 0)
			)
			(min_thickness 0.25)
			(keepout
				(tracks not_allowed)
				(vias allowed)
				(pads allowed)
				(copperpour not_allowed)
				(footprints allowed)
			)
			(placement
				(enabled no)
				(sheetname "")
			)
			(fill
				(thermal_gap 0.5)
				(thermal_bridge_width 0.5)
				(island_removal_mode 0)
			)
			(polygon
				(pts
					(xy 424.190414 -46.4185) (xy 424.190414 -45.399452) (xy 422.101518 -45.399452) (xy 422.101518 -47.488348)
					(xy 424.190414 -47.488348) (xy 424.190414 -46.4439) (xy 424.047666 -46.4439) (xy 424.047666 -47.3456)
					(xy 422.244266 -47.3456) (xy 422.244266 -45.5422) (xy 424.047666 -45.5422) (xy 424.047666 -46.4185)
				)
			)
		)
	)
)
